(kicad_pcb
	(version 20260206)
	(generator "pcbnew")
	(generator_version "10.0")
	(general
		(thickness 1.6)
		(legacy_teardrops no)
	)
	(paper "A4")
	(title_block
		(title "Wiwynn_Tioga_Pass_MB.brd")
		(comment 1 "Tioga Pass / footprints 37-42 of 4770")
	)
	(layers
		(0 "F.Cu" signal "TOP")
		(4 "In1.Cu" signal "L2GND")
		(6 "In2.Cu" signal "L3")
		(8 "In3.Cu" signal "L4GND")
		(10 "In4.Cu" signal "L5")
		(12 "In5.Cu" signal "L6GND")
		(14 "In6.Cu" signal "L7VCC")
		(16 "In7.Cu" signal "L8VCC")
		(18 "In8.Cu" signal "L9GND")
		(20 "In9.Cu" signal "L10")
		(22 "In10.Cu" signal "L11GND")
		(24 "In11.Cu" signal "L12")
		(26 "In12.Cu" signal "L13GND")
		(2 "B.Cu" signal "BOTTOM")
		(9 "F.Adhes" user "F.Adhesive")
		(11 "B.Adhes" user "B.Adhesive")
		(13 "F.Paste" user "Package Geometry/Pastemask Top")
		(15 "B.Paste" user "Package Geometry/Pastemask Bottom")
		(5 "F.SilkS" user "Ref Des/Silkscreen Top")
		(7 "B.SilkS" user "Ref Des/Silkscreen Bottom")
		(1 "F.Mask" user "Board Geometry/Soldermask Top")
		(3 "B.Mask" user "Board Geometry/Soldermask Bottom")
		(17 "Dwgs.User" user "User.Drawings")
		(19 "Cmts.User" user "User.Comments")
		(21 "Eco1.User" user "User.Eco1")
		(23 "Eco2.User" user "User.Eco2")
		(25 "Edge.Cuts" user "Board Geometry/Outline")
		(27 "Margin" user)
		(31 "F.CrtYd" user "Package Geometry/Place Bound Top")
		(29 "B.CrtYd" user "Package Geometry/Place Bound Bottom")
		(35 "F.Fab" user "Ref Des/Assembly Top")
		(33 "B.Fab" user "Ref Des/Assembly Bottom")
	)
	(footprint ""
		(layer "F.Cu")
		(at 385.3942 -153.67)
		(property "Reference" "EU7A2"
			(at 3.98907 0.4318 90)
			(unlocked yes)
			(layer "F.SilkS")
			(effects
				(font
					(size 0.7874 0.5842)
					(thickness 0.1524)
				)
			)
		)
		(property "Value" ""
			(at 0 0 0)
			(layer "F.Fab")
			(effects
				(font
					(size 1.27 1.27)
				)
			)
		)
		(duplicate_pad_numbers_are_jumpers no)
		(fp_line
			(start -3.0099 -3.5052)
			(end 2.9718 -3.5052)
			(stroke
				(width 0.1524)
				(type default)
			)
			(layer "F.SilkS")
		)
		(fp_line
			(start -3.0099 3.429)
			(end -3.0099 -3.5052)
			(stroke
				(width 0.1524)
				(type default)
			)
			(layer "F.SilkS")
		)
		(fp_line
			(start 2.9718 -3.5052)
			(end 2.9718 3.429)
			(stroke
				(width 0.1524)
				(type default)
			)
			(layer "F.SilkS")
		)
		(fp_line
			(start 2.9718 3.429)
			(end -3.0099 3.429)
			(stroke
				(width 0.1524)
				(type default)
			)
			(layer "F.SilkS")
		)
		(fp_circle
			(center -3.057398 -2.678684)
			(end -2.930398 -2.678684)
			(stroke
				(width 0.254)
				(type default)
			)
			(fill no)
			(layer "F.SilkS")
		)
		(fp_poly
			(pts
				(xy -2.9972 -3.4925) (xy -2.9972 -2.6924) (xy -2.1971 -3.4925)
			)
			(stroke
				(width 0)
				(type default)
			)
			(fill yes)
			(layer "F.SilkS")
		)
		(fp_poly
			(pts
				(xy -2.549906 -3.050032) (xy -2.549906 3.050032) (xy 2.549906 3.050032) (xy 2.549906 -3.050032)
			)
			(stroke
				(width 0)
				(type default)
			)
			(fill no)
			(layer "F.CrtYd")
		)
		(fp_line
			(start -2.549906 -3.050032)
			(end 2.549906 -3.050032)
			(stroke
				(width 0.1)
				(type default)
			)
			(layer "F.Fab")
		)
		(fp_line
			(start -2.549906 3.050032)
			(end -2.549906 -3.050032)
			(stroke
				(width 0.1)
				(type default)
			)
			(layer "F.Fab")
		)
		(fp_line
			(start 2.549906 -3.050032)
			(end 2.549906 3.050032)
			(stroke
				(width 0.1)
				(type default)
			)
			(layer "F.Fab")
		)
		(fp_line
			(start 2.549906 3.050032)
			(end -2.549906 3.050032)
			(stroke
				(width 0.1)
				(type default)
			)
			(layer "F.Fab")
		)
		(fp_circle
			(center -3.057398 -2.678684)
			(end -2.930398 -2.678684)
			(stroke
				(width 0.254)
				(type default)
			)
			(fill no)
			(layer "F.Fab")
		)
		(pad "1" smd rect
			(at -2.39522 -2.279904)
			(size 0.7112 0.254)
			(layers "F.Cu" "F.Mask" "F.Paste")
			(net "P1V05_PCH_STBY")
		)
		(pad "2" smd rect
			(at -2.39522 -1.83007)
			(size 0.7112 0.254)
			(layers "F.Cu" "F.Mask" "F.Paste")
			(net "GND")
		)
		(pad "3" smd rect
			(at -2.39522 -1.379982)
			(size 0.7112 0.254)
			(layers "F.Cu" "F.Mask" "F.Paste")
			(net "VR_P1V05_PCH_STBY_PH1_VCIN")
		)
		(pad "4" smd rect
			(at -2.39522 -0.929894)
			(size 0.7112 0.254)
			(layers "F.Cu" "F.Mask" "F.Paste")
			(net "P5V_STBY")
		)
		(pad "5" smd rect
			(at -2.39522 -0.48006)
			(size 0.7112 0.254)
			(layers "F.Cu" "F.Mask" "F.Paste")
			(net "GND")
		)
		(pad "6" smd rect
			(at -2.39522 -0.029972)
			(size 0.7112 0.254)
			(layers "F.Cu" "F.Mask" "F.Paste")
			(net "TP_P1V05_PCH_GL_0")
		)
		(pad "7" smd custom
			(at 0.016764 1.145032)
			(size 0.53975 0.53975)
			(layers "F.Cu" "F.Mask" "F.Paste")
			(net "GND")
			(options
				(clearance outline)
				(anchor circle)
			)
			(primitives
				(gr_poly
					(pts
						(xy -2.7051 1.0795) (xy -2.7051 -0.3683) (xy -0.9271 -0.3683) (xy -0.9271 -1.0795) (xy 2.7051 -1.0795)
						(xy 2.7051 1.0795)
					)
					(width 0)
					(fill yes)
				)
			)
		)
		(pad "10" smd rect
			(at -0.008382 2.874772)
			(size 4.3434 0.6096)
			(layers "F.Cu" "F.Mask" "F.Paste")
			(net "VR_P1V05_PCH_STBY_PH1_PHASE_SW")
		)
		(pad "25" smd rect
			(at 1.548384 -1.283208)
			(size 2.3368 2.0066)
			(layers "F.Cu" "F.Mask" "F.Paste")
			(net "VR_FET_SW_P12V_STBY_PVDDQ_DEF")
		)
		(pad "30" smd rect
			(at 2.050034 -2.895092)
			(size 0.254 0.7112)
			(layers "F.Cu" "F.Mask" "F.Paste")
			(net "VR_FET_SW_P12V_STBY_PVDDQ_DEF")
		)
		(pad "31" smd rect
			(at 1.599946 -2.895092)
			(size 0.254 0.7112)
			(layers "F.Cu" "F.Mask" "F.Paste")
			(net "Net_360")
		)
		(pad "32" smd rect
			(at 1.150112 -2.895092)
			(size 0.254 0.7112)
			(layers "F.Cu" "F.Mask" "F.Paste")
			(net "VR_P1V05_PCH_STBY_PH1_PHASE")
		)
		(pad "33" smd rect
			(at 0.700024 -2.895092)
			(size 0.254 0.7112)
			(layers "F.Cu" "F.Mask" "F.Paste")
			(net "VR_P1V05_PCH_STBY_PH1_BOOT_R")
		)
		(pad "34" smd rect
			(at 0.249936 -2.895092)
			(size 0.254 0.7112)
			(layers "F.Cu" "F.Mask" "F.Paste")
			(net "VR_P1V05_PCH_STBY_PWM1")
		)
		(pad "35" smd rect
			(at -0.199898 -2.895092)
			(size 0.254 0.7112)
			(layers "F.Cu" "F.Mask" "F.Paste")
			(net "P5V_STBY")
		)
		(pad "36" smd rect
			(at -0.649986 -2.895092)
			(size 0.254 0.7112)
			(layers "F.Cu" "F.Mask" "F.Paste")
			(net "A_TSENSE_P1V05_PCH_STBY_TMON")
		)
		(pad "37" smd rect
			(at -1.100074 -2.895092)
			(size 0.254 0.7112)
			(layers "F.Cu" "F.Mask" "F.Paste")
			(net "VR_P1V05_PCH_STBY_OCSET")
		)
		(pad "38" smd rect
			(at -1.549908 -2.895092)
			(size 0.254 0.7112)
			(layers "F.Cu" "F.Mask" "F.Paste")
			(net "ISENSE_P1V05_PCH_STBY_PH1_IMON")
		)
		(pad "39" smd rect
			(at -1.999996 -2.895092)
			(size 0.254 0.7112)
			(layers "F.Cu" "F.Mask" "F.Paste")
			(net "VR_P1V05_PCH_BIREF1")
		)
		(pad "40" smd rect
			(at -0.871728 -1.283208)
			(size 1.8034 2.0066)
			(layers "F.Cu" "F.Mask" "F.Paste")
			(net "GND")
		)
		(pad "41" smd rect
			(at -1.533906 0.247904)
			(size 0.508 0.3556)
			(layers "F.Cu" "F.Mask" "F.Paste")
			(net "TP_P1V05_PCH_GL_1")
		)
	)
	(footprint ""
		(layer "F.Cu")
		(at 397.3576 -0.2286)
		(property "Reference" "R8G15"
			(at 0 0 0)
			(layer "F.SilkS")
			(hide yes)
			(effects
				(font
					(size 1.27 1.27)
				)
			)
		)
		(property "Value" ""
			(at 0 0 0)
			(layer "F.Fab")
			(effects
				(font
					(size 1.27 1.27)
				)
			)
		)
		(duplicate_pad_numbers_are_jumpers no)
		(fp_poly
			(pts
				(xy -0.2794 -0.1016) (xy 0.2794 -0.1016) (xy 0.2794 0.9906) (xy -0.2794 0.9906)
			)
			(stroke
				(width 0)
				(type default)
			)
			(fill no)
			(layer "F.CrtYd")
		)
		(fp_line
			(start -0.2794 -0.1016)
			(end -0.2794 0.9906)
			(stroke
				(width 0.1)
				(type default)
			)
			(layer "F.Fab")
		)
		(fp_line
			(start -0.2794 0.9906)
			(end 0.2794 0.9906)
			(stroke
				(width 0.1)
				(type default)
			)
			(layer "F.Fab")
		)
		(fp_line
			(start 0.2794 -0.1016)
			(end -0.2794 -0.1016)
			(stroke
				(width 0.1)
				(type default)
			)
			(layer "F.Fab")
		)
		(fp_line
			(start 0.2794 0.9906)
			(end 0.2794 -0.1016)
			(stroke
				(width 0.1)
				(type default)
			)
			(layer "F.Fab")
		)
		(pad "1" smd rect
			(at 0 0)
			(size 0.508 0.508)
			(layers "F.Cu" "F.Mask" "F.Paste")
			(net "JTAG_PCH_GBE_CLK")
		)
		(pad "2" smd rect
			(at 0 0.889)
			(size 0.508 0.508)
			(layers "F.Cu" "F.Mask" "F.Paste")
			(net "JTAG_TCK")
		)
		(zone
			(layer "F.Cu")
			(hatch none 0.5)
			(connect_pads
				(clearance 0)
			)
			(min_thickness 0.25)
			(keepout
				(tracks allowed)
				(vias not_allowed)
				(pads allowed)
				(copperpour not_allowed)
				(footprints allowed)
			)
			(placement
				(enabled no)
				(sheetname "")
			)
			(fill
				(thermal_gap 0.5)
				(thermal_bridge_width 0.5)
				(island_removal_mode 0)
			)
			(polygon
				(pts
					(xy 397.1036 0.0254) (xy 397.6116 0.0254) (xy 397.6116 0.4064) (xy 397.1036 0.4064)
				)
			)
		)
		(zone
			(layer "F.Cu")
			(hatch none 0.5)
			(connect_pads
				(clearance 0)
			)
			(min_thickness 0.25)
			(keepout
				(tracks not_allowed)
				(vias allowed)
				(pads allowed)
				(copperpour not_allowed)
				(footprints allowed)
			)
			(placement
				(enabled no)
				(sheetname "")
			)
			(fill
				(thermal_gap 0.5)
				(thermal_bridge_width 0.5)
				(island_removal_mode 0)
			)
			(polygon
				(pts
					(xy 397.1036 0.4064) (xy 397.6116 0.4064) (xy 397.6116 0.0254) (xy 397.1036 0.0254)
				)
			)
		)
	)
	(footprint ""
		(layer "F.Cu")
		(at 23.366984 -94.938596 180)
		(property "Reference" "C1C16"
			(at 0 0 180)
			(layer "F.SilkS")
			(hide yes)
			(effects
				(font
					(size 1.27 1.27)
				)
			)
		)
		(property "Value" ""
			(at 0 0 180)
			(layer "F.Fab")
			(effects
				(font
					(size 1.27 1.27)
				)
			)
		)
		(duplicate_pad_numbers_are_jumpers no)
		(fp_rect
			(start 0.3048 -0.1016)
			(end -0.3048 0.9906)
			(stroke
				(width 0)
				(type default)
			)
			(fill no)
			(layer "F.CrtYd")
		)
		(fp_line
			(start 0.3048 0.9906)
			(end 0.3048 -0.1016)
			(stroke
				(width 0.1)
				(type default)
			)
			(layer "F.Fab")
		)
		(fp_line
			(start 0.3048 -0.1016)
			(end -0.3048 -0.1016)
			(stroke
				(width 0.1)
				(type default)
			)
			(layer "F.Fab")
		)
		(fp_line
			(start -0.3048 0.9906)
			(end 0.3048 0.9906)
			(stroke
				(width 0.1)
				(type default)
			)
			(layer "F.Fab")
		)
		(fp_line
			(start -0.3048 -0.1016)
			(end -0.3048 0.9906)
			(stroke
				(width 0.1)
				(type default)
			)
			(layer "F.Fab")
		)
		(pad "1" smd rect
			(at 0 0 180)
			(size 0.508 0.508)
			(layers "F.Cu" "F.Mask" "F.Paste")
			(net "VSENSE_PVSA_CPU1_BVSP")
		)
		(pad "2" smd rect
			(at 0 0.889 180)
			(size 0.508 0.508)
			(layers "F.Cu" "F.Mask" "F.Paste")
			(net "VSENSE_PVSA_CPU1_N")
		)
		(zone
			(layer "F.Cu")
			(hatch none 0.5)
			(connect_pads
				(clearance 0)
			)
			(min_thickness 0.25)
			(keepout
				(tracks not_allowed)
				(vias allowed)
				(pads allowed)
				(copperpour not_allowed)
				(footprints allowed)
			)
			(placement
				(enabled no)
				(sheetname "")
			)
			(fill
				(thermal_gap 0.5)
				(thermal_bridge_width 0.5)
				(island_removal_mode 0)
			)
			(polygon
				(pts
					(xy 23.112984 -95.192596) (xy 23.620984 -95.192596) (xy 23.620984 -95.573596) (xy 23.112984 -95.573596)
				)
			)
		)
		(zone
			(layer "F.Cu")
			(hatch none 0.5)
			(connect_pads
				(clearance 0)
			)
			(min_thickness 0.25)
			(keepout
				(tracks allowed)
				(vias not_allowed)
				(pads allowed)
				(copperpour not_allowed)
				(footprints allowed)
			)
			(placement
				(enabled no)
				(sheetname "")
			)
			(fill
				(thermal_gap 0.5)
				(thermal_bridge_width 0.5)
				(island_removal_mode 0)
			)
			(polygon
				(pts
					(xy 23.112984 -95.192596) (xy 23.620984 -95.192596) (xy 23.620984 -95.573596) (xy 23.112984 -95.573596)
				)
			)
		)
	)
	(footprint ""
		(layer "F.Cu")
		(at 183.261 -13.335 180)
		(property "Reference" "C4G2"
			(at 0 0 180)
			(layer "F.SilkS")
			(hide yes)
			(effects
				(font
					(size 1.27 1.27)
				)
			)
		)
		(property "Value" ""
			(at 0 0 180)
			(layer "F.Fab")
			(effects
				(font
					(size 1.27 1.27)
				)
			)
		)
		(duplicate_pad_numbers_are_jumpers no)
		(fp_poly
			(pts
				(xy -0.7239 -0.2159) (xy 0.7239 -0.2159) (xy 0.7239 1.9939) (xy -0.7239 1.9939)
			)
			(stroke
				(width 0)
				(type default)
			)
			(fill no)
			(layer "F.CrtYd")
		)
		(fp_line
			(start 0.7239 1.9939)
			(end 0.7239 -0.2159)
			(stroke
				(width 0.1)
				(type default)
			)
			(layer "F.Fab")
		)
		(fp_line
			(start 0.7239 -0.2159)
			(end -0.7239 -0.2159)
			(stroke
				(width 0.1)
				(type default)
			)
			(layer "F.Fab")
		)
		(fp_line
			(start -0.7239 1.9939)
			(end 0.7239 1.9939)
			(stroke
				(width 0.1)
				(type default)
			)
			(layer "F.Fab")
		)
		(fp_line
			(start -0.7239 -0.2159)
			(end -0.7239 1.9939)
			(stroke
				(width 0.1)
				(type default)
			)
			(layer "F.Fab")
		)
		(pad "1" smd rect
			(at 0 0 180)
			(size 1.27 1.016)
			(layers "F.Cu" "F.Mask" "F.Paste")
			(net "VR_FET_SW_P12V_STBY_PVPP_GHJ")
		)
		(pad "2" smd rect
			(at 0 1.778 180)
			(size 1.27 1.016)
			(layers "F.Cu" "F.Mask" "F.Paste")
			(net "GND")
		)
		(zone
			(layer "F.Cu")
			(hatch none 0.5)
			(connect_pads
				(clearance 0)
			)
			(min_thickness 0.25)
			(keepout
				(tracks not_allowed)
				(vias allowed)
				(pads allowed)
				(copperpour not_allowed)
				(footprints allowed)
			)
			(placement
				(enabled no)
				(sheetname "")
			)
			(fill
				(thermal_gap 0.5)
				(thermal_bridge_width 0.5)
				(island_removal_mode 0)
			)
			(polygon
				(pts
					(xy 183.896 -13.843) (xy 182.626 -13.843) (xy 182.626 -14.605) (xy 183.896 -14.605)
				)
			)
		)
	)
	(footprint ""
		(layer "F.Cu")
		(at 5.20446 -132.49402 180)
		(property "Reference" "C1B3"
			(at -0.8382 -0.67818 180)
			(unlocked yes)
			(layer "F.SilkS")
			(effects
				(font
					(size 0.4064 0.254)
					(thickness 0.1524)
				)
				(justify left)
			)
		)
		(property "Value" ""
			(at 0 0 180)
			(layer "F.Fab")
			(effects
				(font
					(size 1.27 1.27)
				)
			)
		)
		(duplicate_pad_numbers_are_jumpers no)
		(fp_poly
			(pts
				(xy 0.3048 -0.1016) (xy 0.3048 0.9906) (xy -0.3048 0.9906) (xy -0.3048 -0.1016)
			)
			(stroke
				(width 0)
				(type default)
			)
			(fill no)
			(layer "F.CrtYd")
		)
		(fp_line
			(start 0.3048 0.9906)
			(end 0.3048 -0.1016)
			(stroke
				(width 0.1)
				(type default)
			)
			(layer "F.Fab")
		)
		(fp_line
			(start 0.3048 -0.1016)
			(end -0.3048 -0.1016)
			(stroke
				(width 0.1)
				(type default)
			)
			(layer "F.Fab")
		)
		(fp_line
			(start -0.3048 0.9906)
			(end 0.3048 0.9906)
			(stroke
				(width 0.1)
				(type default)
			)
			(layer "F.Fab")
		)
		(fp_line
			(start -0.3048 -0.1016)
			(end -0.3048 0.9906)
			(stroke
				(width 0.1)
				(type default)
			)
			(layer "F.Fab")
		)
		(pad "1" smd rect
			(at 0 0 180)
			(size 0.508 0.508)
			(layers "F.Cu" "F.Mask" "F.Paste")
			(net "VR_PVDDQ_KLM_VD12")
		)
		(pad "2" smd rect
			(at 0 0.889 180)
			(size 0.508 0.508)
			(layers "F.Cu" "F.Mask" "F.Paste")
			(net "GND")
		)
		(zone
			(layer "F.Cu")
			(hatch none 0.5)
			(connect_pads
				(clearance 0)
			)
			(min_thickness 0.25)
			(keepout
				(tracks not_allowed)
				(vias allowed)
				(pads allowed)
				(copperpour not_allowed)
				(footprints allowed)
			)
			(placement
				(enabled no)
				(sheetname "")
			)
			(fill
				(thermal_gap 0.5)
				(thermal_bridge_width 0.5)
				(island_removal_mode 0)
			)
			(polygon
				(pts
					(xy 5.45846 -133.12902) (xy 4.95046 -133.12902) (xy 4.95046 -132.74802) (xy 5.45846 -132.74802)
				)
			)
		)
		(zone
			(layer "F.Cu")
			(hatch none 0.5)
			(connect_pads
				(clearance 0)
			)
			(min_thickness 0.25)
			(keepout
				(tracks allowed)
				(vias not_allowed)
				(pads allowed)
				(copperpour not_allowed)
				(footprints allowed)
			)
			(placement
				(enabled no)
				(sheetname "")
			)
			(fill
				(thermal_gap 0.5)
				(thermal_bridge_width 0.5)
				(island_removal_mode 0)
			)
			(polygon
				(pts
					(xy 5.45846 -132.74802) (xy 4.95046 -132.74802) (xy 4.95046 -133.12902) (xy 5.45846 -133.12902)
				)
			)
		)
	)
	(footprint ""
		(layer "F.Cu")
		(at 273.369024 -77.429614)
		(property "Reference" "C5D36"
			(at 0 0 0)
			(layer "F.SilkS")
			(hide yes)
			(effects
				(font
					(size 1.27 1.27)
				)
			)
		)
		(property "Value" ""
			(at 0 0 0)
			(layer "F.Fab")
			(effects
				(font
					(size 1.27 1.27)
				)
			)
		)
		(duplicate_pad_numbers_are_jumpers no)
		(fp_poly
			(pts
				(xy -0.4953 -0.2032) (xy 0.4953 -0.2032) (xy 0.4953 1.6002) (xy -0.4953 1.6002)
			)
			(stroke
				(width 0)
				(type default)
			)
			(fill no)
			(layer "F.CrtYd")
		)
		(fp_line
			(start -0.4953 -0.2032)
			(end 0.4953 -0.2032)
			(stroke
				(width 0.1)
				(type default)
			)
			(layer "F.Fab")
		)
		(fp_line
			(start -0.4953 1.6002)
			(end -0.4953 -0.2032)
			(stroke
				(width 0.1)
				(type default)
			)
			(layer "F.Fab")
		)
		(fp_line
			(start 0.4953 -0.2032)
			(end 0.4953 1.6002)
			(stroke
				(width 0.1)
				(type default)
			)
			(layer "F.Fab")
		)
		(fp_line
			(start 0.4953 1.6002)
			(end -0.4953 1.6002)
			(stroke
				(width 0.1)
				(type default)
			)
			(layer "F.Fab")
		)
		(pad "1" smd rect
			(at 0 0)
			(size 0.762 0.889)
			(layers "F.Cu" "F.Mask" "F.Paste")
			(net "PVCCMCP_CPU0")
		)
		(pad "2" smd rect
			(at 0 1.397)
			(size 0.762 0.889)
			(layers "F.Cu" "F.Mask" "F.Paste")
			(net "GND")
		)
		(zone
			(layer "F.Cu")
			(hatch none 0.5)
			(connect_pads
				(clearance 0)
			)
			(min_thickness 0.25)
			(keepout
				(tracks not_allowed)
				(vias allowed)
				(pads allowed)
				(copperpour not_allowed)
				(footprints allowed)
			)
			(placement
				(enabled no)
				(sheetname "")
			)
			(fill
				(thermal_gap 0.5)
				(thermal_bridge_width 0.5)
				(island_removal_mode 0)
			)
			(polygon
				(pts
					(xy 272.988024 -76.985114) (xy 273.750024 -76.985114) (xy 273.750024 -76.477114) (xy 272.988024 -76.477114)
				)
			)
		)
	)
)
